(kicad_pcb
	(version 20260206)
	(generator "pcbnew")
	(generator_version "10.0")
	(general
		(thickness 1.6)
		(legacy_teardrops no)
	)
	(paper "A4")
	(title_block
		(title "panther-plus-userver — 13130-1b_20150205.brd")
		(comment 1 "Honey Badger (Wiwynn) / footprints 1048-1055 of 1509")
	)
	(layers
		(0 "F.Cu" signal "TOP")
		(4 "In1.Cu" signal "L2")
		(6 "In2.Cu" signal "L3")
		(8 "In3.Cu" signal "L4")
		(10 "In4.Cu" signal "L5")
		(12 "In5.Cu" signal "L6")
		(14 "In6.Cu" signal "L7")
		(16 "In7.Cu" signal "L8")
		(18 "In8.Cu" signal "L9")
		(20 "In9.Cu" signal "L10")
		(22 "In10.Cu" signal "L11")
		(2 "B.Cu" signal "BOTTOM")
		(9 "F.Adhes" user "F.Adhesive")
		(11 "B.Adhes" user "B.Adhesive")
		(13 "F.Paste" user "Package Geometry/Pastemask Top")
		(15 "B.Paste" user "Package Geometry/Pastemask Bottom")
		(5 "F.SilkS" user "Ref Des/Silkscreen Top")
		(7 "B.SilkS" user "Ref Des/Silkscreen Bottom")
		(1 "F.Mask" user "Board Geometry/Soldermask Top")
		(3 "B.Mask" user "Board Geometry/Soldermask Bottom")
		(17 "Dwgs.User" user "User.Drawings")
		(19 "Cmts.User" user "User.Comments")
		(21 "Eco1.User" user "User.Eco1")
		(23 "Eco2.User" user "User.Eco2")
		(25 "Edge.Cuts" user "Board Geometry/Outline")
		(27 "Margin" user)
		(31 "F.CrtYd" user "Package Geometry/Place Bound Top")
		(29 "B.CrtYd" user "Package Geometry/Place Bound Bottom")
		(35 "F.Fab" user "Ref Des/Assembly Top")
		(33 "B.Fab" user "Ref Des/Assembly Bottom")
	)
	(footprint ""
		(layer "B.Cu")
		(at 158.4452 -59.6646)
		(property "Reference" "C325"
			(at 0 0 0)
			(layer "B.SilkS")
			(hide yes)
			(effects
				(font
					(size 1.27 1.27)
				)
				(justify mirror)
			)
		)
		(property "Value" "SCD1U16V2KX-3GP"
			(at -1.8923 -1.2065 0)
			(unlocked yes)
			(layer "B.Fab")
			(hide yes)
			(effects
				(font
					(size 1.016 1.016)
					(thickness 0.1524)
				)
				(justify mirror)
			)
		)
		(property "Device Type" "C402H22"
			(at -1.8923 -2.7305 0)
			(unlocked yes)
			(layer "B.Fab")
			(hide yes)
			(effects
				(font
					(size 1.016 1.016)
					(thickness 0.1524)
				)
				(justify mirror)
			)
		)
		(duplicate_pad_numbers_are_jumpers no)
		(fp_rect
			(start 0.381 0.7366)
			(end -0.381 -0.7366)
			(stroke
				(width 0)
				(type default)
			)
			(fill no)
			(layer "B.CrtYd")
		)
		(fp_rect
			(start 0.381 0.7366)
			(end -0.381 -0.7366)
			(stroke
				(width 0)
				(type default)
			)
			(fill no)
			(layer "B.Fab")
		)
		(pad "1" smd custom
			(at 0 -0.4572 180)
			(size 0.1143 0.1143)
			(layers "B.Cu" "B.Mask" "B.Paste")
			(net "PV_VDDR")
			(options
				(clearance outline)
				(anchor circle)
			)
			(primitives
				(gr_poly
					(pts
						(arc
							(start -0.254 0.1778)
							(mid -0.239121 0.213721)
							(end -0.2032 0.2286)
						)
						(arc
							(start 0.2032 0.2286)
							(mid 0.239121 0.213721)
							(end 0.254 0.1778)
						)
						(arc
							(start 0.254 -0.1778)
							(mid 0.239121 -0.213721)
							(end 0.2032 -0.2286)
						)
						(arc
							(start -0.2032 -0.2286)
							(mid -0.239121 -0.213721)
							(end -0.254 -0.1778)
						)
					)
					(width 0)
					(fill yes)
				)
			)
		)
		(pad "2" smd custom
			(at 0 0.4572 180)
			(size 0.1143 0.1143)
			(layers "B.Cu" "B.Mask" "B.Paste")
			(net "GND")
			(options
				(clearance outline)
				(anchor circle)
			)
			(primitives
				(gr_poly
					(pts
						(arc
							(start -0.254 0.1778)
							(mid -0.239121 0.213721)
							(end -0.2032 0.2286)
						)
						(arc
							(start 0.2032 0.2286)
							(mid 0.239121 0.213721)
							(end 0.254 0.1778)
						)
						(arc
							(start 0.254 -0.1778)
							(mid 0.239121 -0.213721)
							(end 0.2032 -0.2286)
						)
						(arc
							(start -0.2032 -0.2286)
							(mid -0.239121 -0.213721)
							(end -0.254 -0.1778)
						)
					)
					(width 0)
					(fill yes)
				)
			)
		)
	)
	(footprint ""
		(layer "B.Cu")
		(at 40.64 -42.291 180)
		(property "Reference" "C27"
			(at 0 0 0)
			(layer "B.SilkS")
			(hide yes)
			(effects
				(font
					(size 1.27 1.27)
				)
				(justify mirror)
			)
		)
		(property "Value" "SCD1U10V2KX-5GP"
			(at -1.8923 -1.2065 180)
			(unlocked yes)
			(layer "B.Fab")
			(hide yes)
			(effects
				(font
					(size 1.016 1.016)
					(thickness 0.1524)
				)
				(justify mirror)
			)
		)
		(property "Device Type" "C402H22"
			(at -1.8923 -2.7305 180)
			(unlocked yes)
			(layer "B.Fab")
			(hide yes)
			(effects
				(font
					(size 1.016 1.016)
					(thickness 0.1524)
				)
				(justify mirror)
			)
		)
		(duplicate_pad_numbers_are_jumpers no)
		(fp_rect
			(start 0.381 0.7366)
			(end -0.381 -0.7366)
			(stroke
				(width 0)
				(type default)
			)
			(fill no)
			(layer "B.CrtYd")
		)
		(fp_rect
			(start 0.381 0.7366)
			(end -0.381 -0.7366)
			(stroke
				(width 0)
				(type default)
			)
			(fill no)
			(layer "B.Fab")
		)
		(pad "1" smd custom
			(at 0 -0.4572)
			(size 0.1143 0.1143)
			(layers "B.Cu" "B.Mask" "B.Paste")
			(net "P3V3")
			(options
				(clearance outline)
				(anchor circle)
			)
			(primitives
				(gr_poly
					(pts
						(arc
							(start -0.254 0.1778)
							(mid -0.239121 0.213721)
							(end -0.2032 0.2286)
						)
						(arc
							(start 0.2032 0.2286)
							(mid 0.239121 0.213721)
							(end 0.254 0.1778)
						)
						(arc
							(start 0.254 -0.1778)
							(mid 0.239121 -0.213721)
							(end 0.2032 -0.2286)
						)
						(arc
							(start -0.2032 -0.2286)
							(mid -0.239121 -0.213721)
							(end -0.254 -0.1778)
						)
					)
					(width 0)
					(fill yes)
				)
			)
		)
		(pad "2" smd custom
			(at 0 0.4572)
			(size 0.1143 0.1143)
			(layers "B.Cu" "B.Mask" "B.Paste")
			(net "GND")
			(options
				(clearance outline)
				(anchor circle)
			)
			(primitives
				(gr_poly
					(pts
						(arc
							(start -0.254 0.1778)
							(mid -0.239121 0.213721)
							(end -0.2032 0.2286)
						)
						(arc
							(start 0.2032 0.2286)
							(mid 0.239121 0.213721)
							(end 0.254 0.1778)
						)
						(arc
							(start 0.254 -0.1778)
							(mid 0.239121 -0.213721)
							(end 0.2032 -0.2286)
						)
						(arc
							(start -0.2032 -0.2286)
							(mid -0.239121 -0.213721)
							(end -0.254 -0.1778)
						)
					)
					(width 0)
					(fill yes)
				)
			)
		)
	)
	(footprint ""
		(layer "B.Cu")
		(at 81.026 -13.462)
		(property "Reference" "C274"
			(at 0 0 0)
			(layer "B.SilkS")
			(hide yes)
			(effects
				(font
					(size 1.27 1.27)
				)
				(justify mirror)
			)
		)
		(property "Value" "SCD1U16V2KX-3GP"
			(at -1.1811 -2.7051 0)
			(unlocked yes)
			(layer "B.Fab")
			(hide yes)
			(effects
				(font
					(size 1.016 1.016)
					(thickness 0.1524)
				)
				(justify mirror)
			)
		)
		(property "Device Type" "C402H22"
			(at -1.1811 -4.2291 0)
			(unlocked yes)
			(layer "B.Fab")
			(hide yes)
			(effects
				(font
					(size 1.016 1.016)
					(thickness 0.1524)
				)
				(justify mirror)
			)
		)
		(duplicate_pad_numbers_are_jumpers no)
		(fp_rect
			(start 0.381 0.7366)
			(end -0.381 -0.7366)
			(stroke
				(width 0)
				(type default)
			)
			(fill no)
			(layer "B.CrtYd")
		)
		(fp_rect
			(start 0.381 0.7366)
			(end -0.381 -0.7366)
			(stroke
				(width 0)
				(type default)
			)
			(fill no)
			(layer "B.Fab")
		)
		(pad "1" smd custom
			(at 0 -0.4572 180)
			(size 0.1143 0.1143)
			(layers "B.Cu" "B.Mask" "B.Paste")
			(net "P2E_CPU_SAS_C_TX_DP0")
			(options
				(clearance outline)
				(anchor circle)
			)
			(primitives
				(gr_poly
					(pts
						(arc
							(start -0.254 0.1778)
							(mid -0.239121 0.213721)
							(end -0.2032 0.2286)
						)
						(arc
							(start 0.2032 0.2286)
							(mid 0.239121 0.213721)
							(end 0.254 0.1778)
						)
						(arc
							(start 0.254 -0.1778)
							(mid 0.239121 -0.213721)
							(end 0.2032 -0.2286)
						)
						(arc
							(start -0.2032 -0.2286)
							(mid -0.239121 -0.213721)
							(end -0.254 -0.1778)
						)
					)
					(width 0)
					(fill yes)
				)
			)
		)
		(pad "2" smd custom
			(at 0 0.4572 180)
			(size 0.1143 0.1143)
			(layers "B.Cu" "B.Mask" "B.Paste")
			(net "P2E_CPU_SAS_TX_DP0")
			(options
				(clearance outline)
				(anchor circle)
			)
			(primitives
				(gr_poly
					(pts
						(arc
							(start -0.254 0.1778)
							(mid -0.239121 0.213721)
							(end -0.2032 0.2286)
						)
						(arc
							(start 0.2032 0.2286)
							(mid 0.239121 0.213721)
							(end 0.254 0.1778)
						)
						(arc
							(start 0.254 -0.1778)
							(mid 0.239121 -0.213721)
							(end 0.2032 -0.2286)
						)
						(arc
							(start -0.2032 -0.2286)
							(mid -0.239121 -0.213721)
							(end -0.254 -0.1778)
						)
					)
					(width 0)
					(fill yes)
				)
			)
		)
	)
	(footprint ""
		(layer "B.Cu")
		(at 48.133 -15.9004)
		(property "Reference" "R419"
			(at 0 0 0)
			(layer "B.SilkS")
			(hide yes)
			(effects
				(font
					(size 1.27 1.27)
				)
				(justify mirror)
			)
		)
		(property "Value" "33R2F-3-GP"
			(at -1.7907 -1.1176 0)
			(unlocked yes)
			(layer "B.Fab")
			(hide yes)
			(effects
				(font
					(size 1.016 1.016)
					(thickness 0.1524)
				)
				(justify mirror)
			)
		)
		(property "Device Type" "R402H16"
			(at -1.7907 -2.6416 0)
			(unlocked yes)
			(layer "B.Fab")
			(hide yes)
			(effects
				(font
					(size 1.016 1.016)
					(thickness 0.1524)
				)
				(justify mirror)
			)
		)
		(duplicate_pad_numbers_are_jumpers no)
		(fp_rect
			(start 0.381 0.8382)
			(end -0.381 -0.8382)
			(stroke
				(width 0)
				(type default)
			)
			(fill no)
			(layer "B.CrtYd")
		)
		(fp_rect
			(start 0.381 0.8382)
			(end -0.381 -0.8382)
			(stroke
				(width 0)
				(type default)
			)
			(fill no)
			(layer "B.Fab")
		)
		(pad "1" smd custom
			(at 0 -0.4318 180)
			(size 0.127 0.127)
			(layers "B.Cu" "B.Mask" "B.Paste")
			(net "CLK_100M_PCIE2_REFCLK_R_DP")
			(options
				(clearance outline)
				(anchor circle)
			)
			(primitives
				(gr_poly
					(pts
						(arc
							(start -0.2032 0.2794)
							(mid -0.239121 0.264521)
							(end -0.254 0.2286)
						)
						(arc
							(start -0.254 -0.2286)
							(mid -0.239121 -0.264521)
							(end -0.2032 -0.2794)
						)
						(arc
							(start 0.2032 -0.2794)
							(mid 0.239121 -0.264521)
							(end 0.254 -0.2286)
						)
						(arc
							(start 0.254 0.2286)
							(mid 0.239121 0.264521)
							(end 0.2032 0.2794)
						)
					)
					(width 0)
					(fill yes)
				)
			)
		)
		(pad "2" smd custom
			(at 0 0.4318 180)
			(size 0.127 0.127)
			(layers "B.Cu" "B.Mask" "B.Paste")
			(net "CLK_100M_PCIE2_REFCLK_DP")
			(options
				(clearance outline)
				(anchor circle)
			)
			(primitives
				(gr_poly
					(pts
						(arc
							(start -0.2032 0.2794)
							(mid -0.239121 0.264521)
							(end -0.254 0.2286)
						)
						(arc
							(start -0.254 -0.2286)
							(mid -0.239121 -0.264521)
							(end -0.2032 -0.2794)
						)
						(arc
							(start 0.2032 -0.2794)
							(mid 0.239121 -0.264521)
							(end 0.254 -0.2286)
						)
						(arc
							(start 0.254 0.2286)
							(mid 0.239121 0.264521)
							(end 0.2032 0.2794)
						)
					)
					(width 0)
					(fill yes)
				)
			)
		)
	)
	(footprint ""
		(layer "B.Cu")
		(at 36.449 -22.225)
		(property "Reference" "R424"
			(at 0 0 0)
			(layer "B.SilkS")
			(hide yes)
			(effects
				(font
					(size 1.27 1.27)
				)
				(justify mirror)
			)
		)
		(property "Value" "43D2R2F-GP"
			(at -1.7907 -1.1176 0)
			(unlocked yes)
			(layer "B.Fab")
			(hide yes)
			(effects
				(font
					(size 1.016 1.016)
					(thickness 0.1524)
				)
				(justify mirror)
			)
		)
		(property "Device Type" "R402H16"
			(at -1.7907 -2.6416 0)
			(unlocked yes)
			(layer "B.Fab")
			(hide yes)
			(effects
				(font
					(size 1.016 1.016)
					(thickness 0.1524)
				)
				(justify mirror)
			)
		)
		(duplicate_pad_numbers_are_jumpers no)
		(fp_rect
			(start 0.381 0.8382)
			(end -0.381 -0.8382)
			(stroke
				(width 0)
				(type default)
			)
			(fill no)
			(layer "B.CrtYd")
		)
		(fp_rect
			(start 0.381 0.8382)
			(end -0.381 -0.8382)
			(stroke
				(width 0)
				(type default)
			)
			(fill no)
			(layer "B.Fab")
		)
		(pad "1" smd custom
			(at 0 -0.4318 180)
			(size 0.127 0.127)
			(layers "B.Cu" "B.Mask" "B.Paste")
			(net "CLK_100M_CLKBUFF_NGFF_DN")
			(options
				(clearance outline)
				(anchor circle)
			)
			(primitives
				(gr_poly
					(pts
						(arc
							(start -0.2032 0.2794)
							(mid -0.239121 0.264521)
							(end -0.254 0.2286)
						)
						(arc
							(start -0.254 -0.2286)
							(mid -0.239121 -0.264521)
							(end -0.2032 -0.2794)
						)
						(arc
							(start 0.2032 -0.2794)
							(mid 0.239121 -0.264521)
							(end 0.254 -0.2286)
						)
						(arc
							(start 0.254 0.2286)
							(mid 0.239121 0.264521)
							(end 0.2032 0.2794)
						)
					)
					(width 0)
					(fill yes)
				)
			)
		)
		(pad "2" smd custom
			(at 0 0.4318 180)
			(size 0.127 0.127)
			(layers "B.Cu" "B.Mask" "B.Paste")
			(net "GND")
			(options
				(clearance outline)
				(anchor circle)
			)
			(primitives
				(gr_poly
					(pts
						(arc
							(start -0.2032 0.2794)
							(mid -0.239121 0.264521)
							(end -0.254 0.2286)
						)
						(arc
							(start -0.254 -0.2286)
							(mid -0.239121 -0.264521)
							(end -0.2032 -0.2794)
						)
						(arc
							(start 0.2032 -0.2794)
							(mid 0.239121 -0.264521)
							(end 0.254 -0.2286)
						)
						(arc
							(start 0.254 0.2286)
							(mid 0.239121 0.264521)
							(end 0.2032 0.2794)
						)
					)
					(width 0)
					(fill yes)
				)
			)
		)
	)
	(footprint ""
		(layer "B.Cu")
		(at 53.975 -43.434 180)
		(property "Reference" "C23"
			(at 0 0 0)
			(layer "B.SilkS")
			(hide yes)
			(effects
				(font
					(size 1.27 1.27)
				)
				(justify mirror)
			)
		)
		(property "Value" "SCD1U10V2KX-5GP"
			(at -1.8923 -1.2065 180)
			(unlocked yes)
			(layer "B.Fab")
			(hide yes)
			(effects
				(font
					(size 1.016 1.016)
					(thickness 0.1524)
				)
				(justify mirror)
			)
		)
		(property "Device Type" "C402H22"
			(at -1.8923 -2.7305 180)
			(unlocked yes)
			(layer "B.Fab")
			(hide yes)
			(effects
				(font
					(size 1.016 1.016)
					(thickness 0.1524)
				)
				(justify mirror)
			)
		)
		(duplicate_pad_numbers_are_jumpers no)
		(fp_rect
			(start 0.381 0.7366)
			(end -0.381 -0.7366)
			(stroke
				(width 0)
				(type default)
			)
			(fill no)
			(layer "B.CrtYd")
		)
		(fp_rect
			(start 0.381 0.7366)
			(end -0.381 -0.7366)
			(stroke
				(width 0)
				(type default)
			)
			(fill no)
			(layer "B.Fab")
		)
		(pad "1" smd custom
			(at 0 -0.4572)
			(size 0.1143 0.1143)
			(layers "B.Cu" "B.Mask" "B.Paste")
			(net "P3V3")
			(options
				(clearance outline)
				(anchor circle)
			)
			(primitives
				(gr_poly
					(pts
						(arc
							(start -0.254 0.1778)
							(mid -0.239121 0.213721)
							(end -0.2032 0.2286)
						)
						(arc
							(start 0.2032 0.2286)
							(mid 0.239121 0.213721)
							(end 0.254 0.1778)
						)
						(arc
							(start 0.254 -0.1778)
							(mid 0.239121 -0.213721)
							(end 0.2032 -0.2286)
						)
						(arc
							(start -0.2032 -0.2286)
							(mid -0.239121 -0.213721)
							(end -0.254 -0.1778)
						)
					)
					(width 0)
					(fill yes)
				)
			)
		)
		(pad "2" smd custom
			(at 0 0.4572)
			(size 0.1143 0.1143)
			(layers "B.Cu" "B.Mask" "B.Paste")
			(net "GND")
			(options
				(clearance outline)
				(anchor circle)
			)
			(primitives
				(gr_poly
					(pts
						(arc
							(start -0.254 0.1778)
							(mid -0.239121 0.213721)
							(end -0.2032 0.2286)
						)
						(arc
							(start 0.2032 0.2286)
							(mid 0.239121 0.213721)
							(end 0.254 0.1778)
						)
						(arc
							(start 0.254 -0.1778)
							(mid 0.239121 -0.213721)
							(end 0.2032 -0.2286)
						)
						(arc
							(start -0.2032 -0.2286)
							(mid -0.239121 -0.213721)
							(end -0.254 -0.1778)
						)
					)
					(width 0)
					(fill yes)
				)
			)
		)
	)
	(footprint ""
		(layer "B.Cu")
		(at 97.79 -38.735 90)
		(property "Reference" "C186"
			(at 0 0 90)
			(layer "B.SilkS")
			(hide yes)
			(effects
				(font
					(size 1.27 1.27)
				)
				(justify mirror)
			)
		)
		(property "Value" "SC1U10V2KX-1GP"
			(at -1.1811 -2.7051 90)
			(unlocked yes)
			(layer "B.Fab")
			(hide yes)
			(effects
				(font
					(size 1.016 1.016)
					(thickness 0.1524)
				)
				(justify mirror)
			)
		)
		(property "Device Type" "C402H22"
			(at -1.1811 -4.2291 90)
			(unlocked yes)
			(layer "B.Fab")
			(hide yes)
			(effects
				(font
					(size 1.016 1.016)
					(thickness 0.1524)
				)
				(justify mirror)
			)
		)
		(duplicate_pad_numbers_are_jumpers no)
		(fp_rect
			(start 0.381 0.7366)
			(end -0.381 -0.7366)
			(stroke
				(width 0)
				(type default)
			)
			(fill no)
			(layer "B.CrtYd")
		)
		(fp_rect
			(start 0.381 0.7366)
			(end -0.381 -0.7366)
			(stroke
				(width 0)
				(type default)
			)
			(fill no)
			(layer "B.Fab")
		)
		(pad "1" smd custom
			(at 0 -0.4572 270)
			(size 0.1143 0.1143)
			(layers "B.Cu" "B.Mask" "B.Paste")
			(net "P1V1")
			(options
				(clearance outline)
				(anchor circle)
			)
			(primitives
				(gr_poly
					(pts
						(arc
							(start -0.254 0.1778)
							(mid -0.239121 0.213721)
							(end -0.2032 0.2286)
						)
						(arc
							(start 0.2032 0.2286)
							(mid 0.239121 0.213721)
							(end 0.254 0.1778)
						)
						(arc
							(start 0.254 -0.1778)
							(mid 0.239121 -0.213721)
							(end 0.2032 -0.2286)
						)
						(arc
							(start -0.2032 -0.2286)
							(mid -0.239121 -0.213721)
							(end -0.254 -0.1778)
						)
					)
					(width 0)
					(fill yes)
				)
			)
		)
		(pad "2" smd custom
			(at 0 0.4572 270)
			(size 0.1143 0.1143)
			(layers "B.Cu" "B.Mask" "B.Paste")
			(net "GND")
			(options
				(clearance outline)
				(anchor circle)
			)
			(primitives
				(gr_poly
					(pts
						(arc
							(start -0.254 0.1778)
							(mid -0.239121 0.213721)
							(end -0.2032 0.2286)
						)
						(arc
							(start 0.2032 0.2286)
							(mid 0.239121 0.213721)
							(end 0.254 0.1778)
						)
						(arc
							(start 0.254 -0.1778)
							(mid 0.239121 -0.213721)
							(end 0.2032 -0.2286)
						)
						(arc
							(start -0.2032 -0.2286)
							(mid -0.239121 -0.213721)
							(end -0.254 -0.1778)
						)
					)
					(width 0)
					(fill yes)
				)
			)
		)
	)
	(footprint ""
		(layer "B.Cu")
		(at 98.933 -52.705 -90)
		(property "Reference" "R281"
			(at 0 0 90)
			(layer "B.SilkS")
			(hide yes)
			(effects
				(font
					(size 1.27 1.27)
				)
				(justify mirror)
			)
		)
		(property "Value" "100R2F-L1-GP-U"
			(at -0.064008 -3.993896 270)
			(unlocked yes)
			(layer "B.Fab")
			(hide yes)
			(effects
				(font
					(size 1.016 1.016)
					(thickness 0.1524)
				)
				(justify mirror)
			)
		)
		(property "Device Type" "R402H14"
			(at -0.064008 -5.517896 270)
			(unlocked yes)
			(layer "B.Fab")
			(hide yes)
			(effects
				(font
					(size 1.016 1.016)
					(thickness 0.1524)
				)
				(justify mirror)
			)
		)
		(duplicate_pad_numbers_are_jumpers no)
		(fp_rect
			(start 0.381 0.8382)
			(end -0.381 -0.8382)
			(stroke
				(width 0)
				(type default)
			)
			(fill no)
			(layer "B.CrtYd")
		)
		(fp_rect
			(start 0.381 0.8382)
			(end -0.381 -0.8382)
			(stroke
				(width 0)
				(type default)
			)
			(fill no)
			(layer "B.Fab")
		)
		(pad "1" smd custom
			(at 0 -0.4318 90)
			(size 0.127 0.127)
			(layers "B.Cu" "B.Mask" "B.Paste")
			(net "M_A_VREF")
			(options
				(clearance outline)
				(anchor circle)
			)
			(primitives
				(gr_poly
					(pts
						(arc
							(start -0.2032 0.2794)
							(mid -0.239121 0.264521)
							(end -0.254 0.2286)
						)
						(arc
							(start -0.254 -0.2286)
							(mid -0.239121 -0.264521)
							(end -0.2032 -0.2794)
						)
						(arc
							(start 0.2032 -0.2794)
							(mid 0.239121 -0.264521)
							(end 0.254 -0.2286)
						)
						(arc
							(start 0.254 0.2286)
							(mid 0.239121 0.264521)
							(end 0.2032 0.2794)
						)
					)
					(width 0)
					(fill yes)
				)
			)
		)
		(pad "2" smd custom
			(at 0 0.4318 90)
			(size 0.127 0.127)
			(layers "B.Cu" "B.Mask" "B.Paste")
			(net "GND")
			(options
				(clearance outline)
				(anchor circle)
			)
			(primitives
				(gr_poly
					(pts
						(arc
							(start -0.2032 0.2794)
							(mid -0.239121 0.264521)
							(end -0.254 0.2286)
						)
						(arc
							(start -0.254 -0.2286)
							(mid -0.239121 -0.264521)
							(end -0.2032 -0.2794)
						)
						(arc
							(start 0.2032 -0.2794)
							(mid 0.239121 -0.264521)
							(end 0.254 -0.2286)
						)
						(arc
							(start 0.254 0.2286)
							(mid 0.239121 0.264521)
							(end 0.2032 0.2794)
						)
					)
					(width 0)
					(fill yes)
				)
			)
		)
	)
)
